(kicad_pcb
	(version 20260206)
	(generator "pcbnew")
	(generator_version "10.0")
	(general
		(thickness 1.6)
		(legacy_teardrops no)
	)
	(paper "A4")
	(title_block
		(title "12092022_DA0F0TFB6D0_F0T_FAN_BOARD_MP5048_D_brd_v02_OCP.brd")
		(comment 1 "Grand Teton / footprints 878-881 of 924")
	)
	(layers
		(0 "F.Cu" signal "TOP")
		(4 "In1.Cu" signal "GND")
		(6 "In2.Cu" signal "IN1")
		(8 "In3.Cu" signal "IN2")
		(10 "In4.Cu" signal "GND1")
		(2 "B.Cu" signal "BOTTOM")
		(9 "F.Adhes" user "F.Adhesive")
		(11 "B.Adhes" user "B.Adhesive")
		(13 "F.Paste" user "Package Geometry/Pastemask Top")
		(15 "B.Paste" user "Package Geometry/Pastemask Bottom")
		(5 "F.SilkS" user "Ref Des/Silkscreen Top")
		(7 "B.SilkS" user "Ref Des/Silkscreen Bottom")
		(1 "F.Mask" user "Board Geometry/Soldermask Top")
		(3 "B.Mask" user "Board Geometry/Soldermask Bottom")
		(17 "Dwgs.User" user "User.Drawings")
		(19 "Cmts.User" user "User.Comments")
		(21 "Eco1.User" user "User.Eco1")
		(23 "Eco2.User" user "User.Eco2")
		(25 "Edge.Cuts" user "Board Geometry/Outline")
		(27 "Margin" user)
		(31 "F.CrtYd" user "Package Geometry/Place Bound Top")
		(29 "B.CrtYd" user "Package Geometry/Place Bound Bottom")
		(35 "F.Fab" user "Ref Des/Assembly Top")
		(33 "B.Fab" user "Ref Des/Assembly Bottom")
	)
	(footprint ""
		(layer "B.Cu")
		(at 6.700012 -197.01002 180)
		(property "Reference" "J7"
			(at 2.763012 19.24431 0)
			(unlocked yes)
			(layer "B.SilkS")
			(effects
				(font
					(size 0.7874 0.5842)
					(thickness 0.1524)
				)
				(justify left mirror)
			)
		)
		(property "Value" ""
			(at 0 0 0)
			(layer "B.Fab")
			(effects
				(font
					(size 1.27 1.27)
				)
				(justify mirror)
			)
		)
		(duplicate_pad_numbers_are_jumpers no)
		(fp_line
			(start 4.350004 18.524982)
			(end -6.35 18.524982)
			(stroke
				(width 0.1524)
				(type default)
			)
			(layer "B.SilkS")
		)
		(fp_line
			(start 4.350004 -4.52501)
			(end 4.350004 18.524982)
			(stroke
				(width 0.1524)
				(type default)
			)
			(layer "B.SilkS")
		)
		(fp_line
			(start 1.249934 15.424912)
			(end -3.24993 15.424912)
			(stroke
				(width 0.1524)
				(type default)
			)
			(layer "B.SilkS")
		)
		(fp_line
			(start 1.249934 8.200136)
			(end 4.350004 8.200136)
			(stroke
				(width 0.1524)
				(type default)
			)
			(layer "B.SilkS")
		)
		(fp_line
			(start 1.249934 8.200136)
			(end 1.249934 15.424912)
			(stroke
				(width 0.1524)
				(type default)
			)
			(layer "B.SilkS")
		)
		(fp_line
			(start 1.249934 5.799836)
			(end 4.350004 5.799836)
			(stroke
				(width 0.1524)
				(type default)
			)
			(layer "B.SilkS")
		)
		(fp_line
			(start 1.249934 -1.42494)
			(end 1.249934 5.799836)
			(stroke
				(width 0.1524)
				(type default)
			)
			(layer "B.SilkS")
		)
		(fp_line
			(start -0.029972 -1.42494)
			(end 1.249934 -1.42494)
			(stroke
				(width 0.1524)
				(type default)
			)
			(layer "B.SilkS")
		)
		(fp_line
			(start -3.24993 15.424912)
			(end -3.24993 -1.42494)
			(stroke
				(width 0.1524)
				(type default)
			)
			(layer "B.SilkS")
		)
		(fp_line
			(start -3.24993 -1.42494)
			(end -1.96977 -1.42494)
			(stroke
				(width 0.1524)
				(type default)
			)
			(layer "B.SilkS")
		)
		(fp_line
			(start -6.35 18.524982)
			(end -6.35 -4.52501)
			(stroke
				(width 0.1524)
				(type default)
			)
			(layer "B.SilkS")
		)
		(fp_line
			(start -6.35 -4.52501)
			(end 4.350004 -4.52501)
			(stroke
				(width 0.1524)
				(type default)
			)
			(layer "B.SilkS")
		)
		(fp_poly
			(pts
				(xy 5.527802 -0.508) (xy 5.527802 0.508) (xy 4.511802 0)
			)
			(stroke
				(width 0)
				(type default)
			)
			(fill yes)
			(layer "B.SilkS")
		)
		(fp_line
			(start 4.350004 18.524982)
			(end -6.35 18.524982)
			(stroke
				(width 0.1)
				(type default)
			)
			(layer "B.Fab")
		)
		(fp_line
			(start 4.350004 -4.52501)
			(end 4.350004 18.524982)
			(stroke
				(width 0.1)
				(type default)
			)
			(layer "B.Fab")
		)
		(fp_line
			(start -6.35 18.524982)
			(end -6.35 -4.52501)
			(stroke
				(width 0.1)
				(type default)
			)
			(layer "B.Fab")
		)
		(fp_line
			(start -6.35 -4.52501)
			(end 4.350004 -4.52501)
			(stroke
				(width 0.1)
				(type default)
			)
			(layer "B.Fab")
		)
		(fp_poly
			(pts
				(xy 5.527802 -0.508) (xy 5.527802 0.508) (xy 4.511802 0)
			)
			(stroke
				(width 0)
				(type default)
			)
			(fill yes)
			(layer "B.Fab")
		)
		(pad "" np_thru_hole circle
			(at -0.999998 -1.89992 90)
			(size 1.4986 1.4986)
			(drill 1.4986)
			(layers "*.Cu" "*.Mask")
			(clearance 0.381)
			(thermal_gap 0.381)
		)
		(pad "1" thru_hole rect
			(at 0 0 90)
			(size 1.3716 1.3716)
			(drill 0.9652)
			(layers "*.Cu" "*.Mask")
			(remove_unused_layers no)
			(net "FAN_6_TACH_IL_D")
			(clearance 0.0508)
			(padstack
				(mode front_inner_back)
				(layer "Inner"
					(shape circle)
					(size 1.3716 1.3716)
					(clearance 0.0508)
				)
				(layer "B.Cu"
					(shape rect)
					(size 1.3716 1.3716)
					(thermal_gap 0.0508)
					(clearance 0.0508)
				)
			)
		)
		(pad "2" thru_hole circle
			(at -1.999996 0 90)
			(size 1.3716 1.3716)
			(drill 0.9652)
			(layers "*.Cu" "*.Mask")
			(remove_unused_layers no)
			(net "FAN_6_PWM_OL_R")
			(clearance 0.0508)
			(thermal_gap 0.0508)
		)
		(pad "3" thru_hole circle
			(at 0 1.999996 90)
			(size 1.3716 1.3716)
			(drill 0.9652)
			(layers "*.Cu" "*.Mask")
			(remove_unused_layers no)
			(net "FAN_6_PWM_IL_R")
			(clearance 0.0508)
			(thermal_gap 0.0508)
		)
		(pad "4" thru_hole circle
			(at -1.999996 1.999996 90)
			(size 1.3716 1.3716)
			(drill 0.9652)
			(layers "*.Cu" "*.Mask")
			(remove_unused_layers no)
			(net "FAN_6_PRESENT_R_N")
			(clearance 0.0508)
			(thermal_gap 0.0508)
		)
		(pad "5" thru_hole circle
			(at 0 3.999992 90)
			(size 1.3716 1.3716)
			(drill 0.9652)
			(layers "*.Cu" "*.Mask")
			(remove_unused_layers no)
			(net "P12V_LED_R1_FAN6")
			(clearance 0.0508)
			(thermal_gap 0.0508)
		)
		(pad "6" thru_hole circle
			(at -1.999996 3.999992 90)
			(size 1.3716 1.3716)
			(drill 0.9652)
			(layers "*.Cu" "*.Mask")
			(remove_unused_layers no)
			(net "SMB_FAN6_SCL_R")
			(clearance 0.0508)
			(thermal_gap 0.0508)
		)
		(pad "7" thru_hole circle
			(at 0 5.999988 90)
			(size 1.3716 1.3716)
			(drill 0.9652)
			(layers "*.Cu" "*.Mask")
			(remove_unused_layers no)
			(net "SMB_FAN6_SDA_R")
			(clearance 0.0508)
			(thermal_gap 0.0508)
		)
		(pad "8" thru_hole circle
			(at -1.999996 5.999988 90)
			(size 1.3716 1.3716)
			(drill 0.9652)
			(layers "*.Cu" "*.Mask")
			(remove_unused_layers no)
			(net "GND")
			(clearance 0.0508)
			(thermal_gap 0.0508)
		)
		(pad "9" thru_hole circle
			(at 0 7.999984 90)
			(size 1.3716 1.3716)
			(drill 0.9652)
			(layers "*.Cu" "*.Mask")
			(remove_unused_layers no)
			(net "GND")
			(clearance 0.0508)
			(thermal_gap 0.0508)
		)
		(pad "10" thru_hole circle
			(at -1.999996 7.999984 90)
			(size 1.3716 1.3716)
			(drill 0.9652)
			(layers "*.Cu" "*.Mask")
			(remove_unused_layers no)
			(net "P52V_FAN_6")
			(clearance 0.0508)
			(thermal_gap 0.0508)
		)
		(pad "11" thru_hole circle
			(at 0 9.99998 90)
			(size 1.3716 1.3716)
			(drill 0.9652)
			(layers "*.Cu" "*.Mask")
			(remove_unused_layers no)
			(net "P52V_FAN_6")
			(clearance 0.0508)
			(thermal_gap 0.0508)
		)
		(pad "12" thru_hole circle
			(at -1.999996 9.99998 90)
			(size 1.3716 1.3716)
			(drill 0.9652)
			(layers "*.Cu" "*.Mask")
			(remove_unused_layers no)
			(net "FAN_6_FAIL_R_LED_N")
			(clearance 0.0508)
			(thermal_gap 0.0508)
		)
		(pad "13" thru_hole circle
			(at 0 11.999976 90)
			(size 1.3716 1.3716)
			(drill 0.9652)
			(layers "*.Cu" "*.Mask")
			(remove_unused_layers no)
			(net "FAN_6_TACH_OL_D")
			(clearance 0.0508)
			(thermal_gap 0.0508)
		)
		(pad "14" thru_hole circle
			(at -1.999996 11.999976 90)
			(size 1.3716 1.3716)
			(drill 0.9652)
			(layers "*.Cu" "*.Mask")
			(remove_unused_layers no)
			(net "FAN_6_OK_R_LED_N")
			(clearance 0.0508)
			(thermal_gap 0.0508)
		)
		(pad "15" thru_hole circle
			(at 0 13.999972 90)
			(size 1.3716 1.3716)
			(drill 0.9652)
			(layers "*.Cu" "*.Mask")
			(remove_unused_layers no)
			(net "Net_600")
			(clearance 0.0508)
			(thermal_gap 0.0508)
		)
		(pad "16" thru_hole circle
			(at -1.999996 13.999972 90)
			(size 1.3716 1.3716)
			(drill 0.9652)
			(layers "*.Cu" "*.Mask")
			(remove_unused_layers no)
			(net "Net_599")
			(clearance 0.0508)
			(thermal_gap 0.0508)
		)
		(zone
			(layers "F.Cu" "B.Cu" "In1.Cu" "In2.Cu" "In3.Cu" "In4.Cu")
			(hatch none 0.5)
			(connect_pads
				(clearance 0)
			)
			(min_thickness 0.25)
			(keepout
				(tracks not_allowed)
				(vias allowed)
				(pads allowed)
				(copperpour not_allowed)
				(footprints allowed)
			)
			(placement
				(enabled no)
				(sheetname "")
			)
			(fill
				(thermal_gap 0.5)
				(thermal_bridge_width 0.5)
				(island_removal_mode 0)
			)
			(polygon
				(pts
					(arc
						(start 8.95731 -195.1101)
						(mid 6.44271 -195.1101)
						(end 8.95731 -195.1101)
					)
				)
			)
		)
	)
	(footprint ""
		(layer "B.Cu")
		(at 17.653 -126.238 180)
		(property "Reference" "R5434"
			(at 0 0 0)
			(layer "B.SilkS")
			(hide yes)
			(effects
				(font
					(size 1.27 1.27)
				)
				(justify mirror)
			)
		)
		(property "Value" ""
			(at 0 0 0)
			(layer "B.Fab")
			(effects
				(font
					(size 1.27 1.27)
				)
				(justify mirror)
			)
		)
		(duplicate_pad_numbers_are_jumpers no)
		(fp_line
			(start 0.7874 0.4064)
			(end 0.7874 -0.4064)
			(stroke
				(width 0.1524)
				(type default)
			)
			(layer "B.SilkS")
		)
		(fp_line
			(start 0.7874 -0.4064)
			(end -0.7874 -0.4064)
			(stroke
				(width 0.1524)
				(type default)
			)
			(layer "B.SilkS")
		)
		(fp_line
			(start -0.7874 0.4064)
			(end 0.7874 0.4064)
			(stroke
				(width 0.1524)
				(type default)
			)
			(layer "B.SilkS")
		)
		(fp_line
			(start -0.7874 -0.4064)
			(end -0.7874 0.4064)
			(stroke
				(width 0.1524)
				(type default)
			)
			(layer "B.SilkS")
		)
		(fp_line
			(start 0.67945 0.3048)
			(end 0.67945 -0.305054)
			(stroke
				(width 0.1)
				(type default)
			)
			(layer "B.Fab")
		)
		(fp_line
			(start 0.67945 -0.305054)
			(end 0.12065 -0.305054)
			(stroke
				(width 0.1)
				(type default)
			)
			(layer "B.Fab")
		)
		(fp_line
			(start 0.12065 0.3048)
			(end 0.67945 0.3048)
			(stroke
				(width 0.1)
				(type default)
			)
			(layer "B.Fab")
		)
		(fp_line
			(start 0.12065 0.2794)
			(end 0.12065 0.3048)
			(stroke
				(width 0.1)
				(type default)
			)
			(layer "B.Fab")
		)
		(fp_line
			(start 0.12065 -0.2794)
			(end -0.12065 -0.2794)
			(stroke
				(width 0.1)
				(type default)
			)
			(layer "B.Fab")
		)
		(fp_line
			(start 0.12065 -0.305054)
			(end 0.12065 -0.2794)
			(stroke
				(width 0.1)
				(type default)
			)
			(layer "B.Fab")
		)
		(fp_line
			(start -0.120396 0.3048)
			(end -0.120396 0.2794)
			(stroke
				(width 0.1)
				(type default)
			)
			(layer "B.Fab")
		)
		(fp_line
			(start -0.120396 0.2794)
			(end 0.12065 0.2794)
			(stroke
				(width 0.1)
				(type default)
			)
			(layer "B.Fab")
		)
		(fp_line
			(start -0.12065 -0.2794)
			(end -0.12065 -0.3048)
			(stroke
				(width 0.1)
				(type default)
			)
			(layer "B.Fab")
		)
		(fp_line
			(start -0.12065 -0.3048)
			(end -0.67945 -0.3048)
			(stroke
				(width 0.1)
				(type default)
			)
			(layer "B.Fab")
		)
		(fp_line
			(start -0.67945 0.3048)
			(end -0.120396 0.3048)
			(stroke
				(width 0.1)
				(type default)
			)
			(layer "B.Fab")
		)
		(fp_line
			(start -0.67945 -0.3048)
			(end -0.67945 0.3048)
			(stroke
				(width 0.1)
				(type default)
			)
			(layer "B.Fab")
		)
		(pad "1" smd rect
			(at 0.40005 0 180)
			(size 0.4572 0.508)
			(layers "B.Cu" "B.Mask" "B.Paste")
			(net "FAN_4_TACH_IL")
		)
		(pad "2" smd rect
			(at -0.40005 0 180)
			(size 0.4572 0.508)
			(layers "B.Cu" "B.Mask" "B.Paste")
			(net "GND")
		)
	)
	(footprint ""
		(layer "B.Cu")
		(at 38.46068 -258.562856 90)
		(property "Reference" "PR8"
			(at 0 0 90)
			(layer "B.SilkS")
			(hide yes)
			(effects
				(font
					(size 1.27 1.27)
				)
				(justify mirror)
			)
		)
		(property "Value" ""
			(at 0 0 90)
			(layer "B.Fab")
			(effects
				(font
					(size 1.27 1.27)
				)
				(justify mirror)
			)
		)
		(duplicate_pad_numbers_are_jumpers no)
		(fp_line
			(start 0.7874 -0.4064)
			(end -0.7874 -0.4064)
			(stroke
				(width 0.1524)
				(type default)
			)
			(layer "B.SilkS")
		)
		(fp_line
			(start -0.7874 -0.4064)
			(end -0.7874 0.4064)
			(stroke
				(width 0.1524)
				(type default)
			)
			(layer "B.SilkS")
		)
		(fp_line
			(start 0.7874 0.4064)
			(end 0.7874 -0.4064)
			(stroke
				(width 0.1524)
				(type default)
			)
			(layer "B.SilkS")
		)
		(fp_line
			(start -0.7874 0.4064)
			(end 0.7874 0.4064)
			(stroke
				(width 0.1524)
				(type default)
			)
			(layer "B.SilkS")
		)
		(fp_line
			(start 0.67945 -0.305054)
			(end 0.12065 -0.305054)
			(stroke
				(width 0.1)
				(type default)
			)
			(layer "B.Fab")
		)
		(fp_line
			(start 0.12065 -0.305054)
			(end 0.12065 -0.2794)
			(stroke
				(width 0.1)
				(type default)
			)
			(layer "B.Fab")
		)
		(fp_line
			(start -0.12065 -0.3048)
			(end -0.67945 -0.3048)
			(stroke
				(width 0.1)
				(type default)
			)
			(layer "B.Fab")
		)
		(fp_line
			(start -0.67945 -0.3048)
			(end -0.67945 0.3048)
			(stroke
				(width 0.1)
				(type default)
			)
			(layer "B.Fab")
		)
		(fp_line
			(start 0.12065 -0.2794)
			(end -0.12065 -0.2794)
			(stroke
				(width 0.1)
				(type default)
			)
			(layer "B.Fab")
		)
		(fp_line
			(start -0.12065 -0.2794)
			(end -0.12065 -0.3048)
			(stroke
				(width 0.1)
				(type default)
			)
			(layer "B.Fab")
		)
		(fp_line
			(start 0.12065 0.2794)
			(end 0.12065 0.3048)
			(stroke
				(width 0.1)
				(type default)
			)
			(layer "B.Fab")
		)
		(fp_line
			(start -0.120396 0.2794)
			(end 0.12065 0.2794)
			(stroke
				(width 0.1)
				(type default)
			)
			(layer "B.Fab")
		)
		(fp_line
			(start 0.67945 0.3048)
			(end 0.67945 -0.305054)
			(stroke
				(width 0.1)
				(type default)
			)
			(layer "B.Fab")
		)
		(fp_line
			(start 0.12065 0.3048)
			(end 0.67945 0.3048)
			(stroke
				(width 0.1)
				(type default)
			)
			(layer "B.Fab")
		)
		(fp_line
			(start -0.120396 0.3048)
			(end -0.120396 0.2794)
			(stroke
				(width 0.1)
				(type default)
			)
			(layer "B.Fab")
		)
		(fp_line
			(start -0.67945 0.3048)
			(end -0.120396 0.3048)
			(stroke
				(width 0.1)
				(type default)
			)
			(layer "B.Fab")
		)
		(pad "1" smd circle
			(at 0.40005 0 270)
			(size 0 0)
			(layers "B.Cu" "B.Mask" "B.Paste")
			(net "FAN_0_TEMP")
		)
		(pad "2" smd circle
			(at -0.40005 0 270)
			(size 0 0)
			(layers "B.Cu" "B.Mask" "B.Paste")
			(net "GND")
		)
	)
	(footprint ""
		(layer "B.Cu")
		(at 8.763 -249.428 -90)
		(property "Reference" "PC51"
			(at 0 0 90)
			(layer "B.SilkS")
			(hide yes)
			(effects
				(font
					(size 1.27 1.27)
				)
				(justify mirror)
			)
		)
		(property "Value" ""
			(at 0 0 90)
			(layer "B.Fab")
			(effects
				(font
					(size 1.27 1.27)
				)
				(justify mirror)
			)
		)
		(duplicate_pad_numbers_are_jumpers no)
		(fp_line
			(start -0.7874 0.4064)
			(end 0.7874 0.4064)
			(stroke
				(width 0.1524)
				(type default)
			)
			(layer "B.SilkS")
		)
		(fp_line
			(start 0.7874 0.4064)
			(end 0.7874 -0.4064)
			(stroke
				(width 0.1524)
				(type default)
			)
			(layer "B.SilkS")
		)
		(fp_line
			(start -0.7874 -0.4064)
			(end -0.7874 0.4064)
			(stroke
				(width 0.1524)
				(type default)
			)
			(layer "B.SilkS")
		)
		(fp_line
			(start 0.7874 -0.4064)
			(end -0.7874 -0.4064)
			(stroke
				(width 0.1524)
				(type default)
			)
			(layer "B.SilkS")
		)
		(fp_line
			(start -0.67945 0.3048)
			(end -0.120396 0.3048)
			(stroke
				(width 0.1)
				(type default)
			)
			(layer "B.Fab")
		)
		(fp_line
			(start -0.120396 0.3048)
			(end -0.120396 0.2794)
			(stroke
				(width 0.1)
				(type default)
			)
			(layer "B.Fab")
		)
		(fp_line
			(start 0.12065 0.3048)
			(end 0.67945 0.3048)
			(stroke
				(width 0.1)
				(type default)
			)
			(layer "B.Fab")
		)
		(fp_line
			(start 0.67945 0.3048)
			(end 0.67945 -0.305054)
			(stroke
				(width 0.1)
				(type default)
			)
			(layer "B.Fab")
		)
		(fp_line
			(start -0.120396 0.2794)
			(end 0.12065 0.2794)
			(stroke
				(width 0.1)
				(type default)
			)
			(layer "B.Fab")
		)
		(fp_line
			(start 0.12065 0.2794)
			(end 0.12065 0.3048)
			(stroke
				(width 0.1)
				(type default)
			)
			(layer "B.Fab")
		)
		(fp_line
			(start -0.12065 -0.2794)
			(end -0.12065 -0.3048)
			(stroke
				(width 0.1)
				(type default)
			)
			(layer "B.Fab")
		)
		(fp_line
			(start 0.12065 -0.2794)
			(end -0.12065 -0.2794)
			(stroke
				(width 0.1)
				(type default)
			)
			(layer "B.Fab")
		)
		(fp_line
			(start -0.67945 -0.3048)
			(end -0.67945 0.3048)
			(stroke
				(width 0.1)
				(type default)
			)
			(layer "B.Fab")
		)
		(fp_line
			(start -0.12065 -0.3048)
			(end -0.67945 -0.3048)
			(stroke
				(width 0.1)
				(type default)
			)
			(layer "B.Fab")
		)
		(fp_line
			(start 0.12065 -0.305054)
			(end 0.12065 -0.2794)
			(stroke
				(width 0.1)
				(type default)
			)
			(layer "B.Fab")
		)
		(fp_line
			(start 0.67945 -0.305054)
			(end 0.12065 -0.305054)
			(stroke
				(width 0.1)
				(type default)
			)
			(layer "B.Fab")
		)
		(pad "1" smd circle
			(at 0.40005 0 90)
			(size 0 0)
			(layers "B.Cu" "B.Mask" "B.Paste")
			(net "FAN_6_P5V")
		)
		(pad "2" smd circle
			(at -0.40005 0 90)
			(size 0 0)
			(layers "B.Cu" "B.Mask" "B.Paste")
			(net "GND")
		)
	)
)
